# BASEBOARD_FAB2 (Tioga Pass) — schematic netlist excerpt (pin names and nets, part order shuffled) for the footprints in the layout excerpt that follows; sources: Cadence DE-HDL packaged netlist, KiCad conversion of Wiwynn_Tioga_Pass_MB.brd

U8D3  TTL1G07_A  74LVC1G07 IC  pkg SOP  page 170 : A = IRQ_SML1_PMBUS_ALERT_BUF_N ; Y = IRQ_FORCE_NM_THROTTLE_R_N
C1B6  CAP_A  1.0UF 6.3V 10% X6S  pkg 0402V  page 226 : A = VR_PVDDQ_KLM_VDD ; B = GND
C8A3  CAP_A  0.1UF 16V 10% X7R  pkg 0402V  page 235 : A = VR_PVNN_PCH_VINSEN ; B = GND

(kicad_pcb
	(version 20260206)
	(generator "pcbnew")
	(generator_version "10.0")
	(general
		(thickness 1.6)
		(legacy_teardrops no)
	)
	(paper "A4")
	(title_block
		(title "Wiwynn_Tioga_Pass_MB.brd")
		(comment 1 "Tioga Pass / footprints 80-82 of 4770")
	)
	(layers
		(0 "F.Cu" signal "TOP")
		(4 "In1.Cu" signal "L2GND")
		(6 "In2.Cu" signal "L3")
		(8 "In3.Cu" signal "L4GND")
		(10 "In4.Cu" signal "L5")
		(12 "In5.Cu" signal "L6GND")
		(14 "In6.Cu" signal "L7VCC")
		(16 "In7.Cu" signal "L8VCC")
		(18 "In8.Cu" signal "L9GND")
		(20 "In9.Cu" signal "L10")
		(22 "In10.Cu" signal "L11GND")
		(24 "In11.Cu" signal "L12")
		(26 "In12.Cu" signal "L13GND")
		(2 "B.Cu" signal "BOTTOM")
		(9 "F.Adhes" user "F.Adhesive")
		(11 "B.Adhes" user "B.Adhesive")
		(13 "F.Paste" user "Package Geometry/Pastemask Top")
		(15 "B.Paste" user "Package Geometry/Pastemask Bottom")
		(5 "F.SilkS" user "Ref Des/Silkscreen Top")
		(7 "B.SilkS" user "Ref Des/Silkscreen Bottom")
		(1 "F.Mask" user "Board Geometry/Soldermask Top")
		(3 "B.Mask" user "Board Geometry/Soldermask Bottom")
		(17 "Dwgs.User" user "User.Drawings")
		(19 "Cmts.User" user "User.Comments")
		(21 "Eco1.User" user "User.Eco1")
		(23 "Eco2.User" user "User.Eco2")
		(25 "Edge.Cuts" user "Board Geometry/Outline")
		(27 "Margin" user)
		(31 "F.CrtYd" user "Package Geometry/Place Bound Top")
		(29 "B.CrtYd" user "Package Geometry/Place Bound Bottom")
		(35 "F.Fab" user "Ref Des/Assembly Top")
		(33 "B.Fab" user "Ref Des/Assembly Bottom")
	)
	(footprint ""
		(layer "F.Cu")
		(at 391.55624 -152.008586 -90)
		(property "Reference" "C8A3"
			(at 0 0 270)
			(layer "F.SilkS")
			(hide yes)
			(effects
				(font
					(size 1.27 1.27)
				)
			)
		)
		(property "Value" ""
			(at 0 0 270)
			(layer "F.Fab")
			(effects
				(font
					(size 1.27 1.27)
				)
			)
		)
		(duplicate_pad_numbers_are_jumpers no)
		(fp_poly
			(pts
				(xy 0.3048 -0.1016) (xy 0.3048 0.9906) (xy -0.3048 0.9906) (xy -0.3048 -0.1016)
			)
			(stroke
				(width 0)
				(type default)
			)
			(fill no)
			(layer "F.CrtYd")
		)
		(fp_line
			(start -0.3048 0.9906)
			(end 0.3048 0.9906)
			(stroke
				(width 0.1)
				(type default)
			)
			(layer "F.Fab")
		)
		(fp_line
			(start 0.3048 0.9906)
			(end 0.3048 -0.1016)
			(stroke
				(width 0.1)
				(type default)
			)
			(layer "F.Fab")
		)
		(fp_line
			(start -0.3048 -0.1016)
			(end -0.3048 0.9906)
			(stroke
				(width 0.1)
				(type default)
			)
			(layer "F.Fab")
		)
		(fp_line
			(start 0.3048 -0.1016)
			(end -0.3048 -0.1016)
			(stroke
				(width 0.1)
				(type default)
			)
			(layer "F.Fab")
		)
		(pad "1" smd rect
			(at 0 0 270)
			(size 0.508 0.508)
			(layers "F.Cu" "F.Mask" "F.Paste")
			(net "VR_PVNN_PCH_VINSEN")
		)
		(pad "2" smd rect
			(at 0 0.889 270)
			(size 0.508 0.508)
			(layers "F.Cu" "F.Mask" "F.Paste")
			(net "GND")
		)
		(zone
			(layer "F.Cu")
			(hatch none 0.5)
			(connect_pads
				(clearance 0)
			)
			(min_thickness 0.25)
			(keepout
				(tracks not_allowed)
				(vias allowed)
				(pads allowed)
				(copperpour not_allowed)
				(footprints allowed)
			)
			(placement
				(enabled no)
				(sheetname "")
			)
			(fill
				(thermal_gap 0.5)
				(thermal_bridge_width 0.5)
				(island_removal_mode 0)
			)
			(polygon
				(pts
					(xy 390.92124 -152.262586) (xy 390.92124 -151.754586) (xy 391.30224 -151.754586) (xy 391.30224 -152.262586)
				)
			)
		)
		(zone
			(layer "F.Cu")
			(hatch none 0.5)
			(connect_pads
				(clearance 0)
			)
			(min_thickness 0.25)
			(keepout
				(tracks allowed)
				(vias not_allowed)
				(pads allowed)
				(copperpour not_allowed)
				(footprints allowed)
			)
			(placement
				(enabled no)
				(sheetname "")
			)
			(fill
				(thermal_gap 0.5)
				(thermal_bridge_width 0.5)
				(island_removal_mode 0)
			)
			(polygon
				(pts
					(xy 391.30224 -152.262586) (xy 391.30224 -151.754586) (xy 390.92124 -151.754586) (xy 390.92124 -152.262586)
				)
			)
		)
	)
	(footprint ""
		(layer "F.Cu")
		(at 420.751 -79.614014 180)
		(property "Reference" "U8D3"
			(at 3.09753 1.21666 270)
			(unlocked yes)
			(layer "F.SilkS")
			(effects
				(font
					(size 0.7874 0.5842)
					(thickness 0.1524)
				)
				(justify left)
			)
		)
		(property "Value" ""
			(at 0 0 180)
			(layer "F.Fab")
			(effects
				(font
					(size 1.27 1.27)
				)
			)
		)
		(duplicate_pad_numbers_are_jumpers no)
		(fp_circle
			(center -0.4699 -0.8382)
			(end -0.5969 -0.8382)
			(stroke
				(width 0.254)
				(type default)
			)
			(fill no)
			(layer "F.SilkS")
		)
		(fp_poly
			(pts
				(xy 0.21463 -0.450088) (xy 1.56337 -0.450088) (xy 1.56337 1.75006) (xy 0.21463 1.75006)
			)
			(stroke
				(width 0)
				(type default)
			)
			(fill no)
			(layer "F.CrtYd")
		)
		(fp_line
			(start 1.56337 1.75006)
			(end 0.21463 1.75006)
			(stroke
				(width 0.1)
				(type default)
			)
			(layer "F.Fab")
		)
		(fp_line
			(start 1.56337 -0.450088)
			(end 1.56337 1.75006)
			(stroke
				(width 0.1)
				(type default)
			)
			(layer "F.Fab")
		)
		(fp_line
			(start 0.21463 1.75006)
			(end 0.21463 -0.450088)
			(stroke
				(width 0.1)
				(type default)
			)
			(layer "F.Fab")
		)
		(fp_line
			(start 0.21463 -0.450088)
			(end 1.56337 -0.450088)
			(stroke
				(width 0.1)
				(type default)
			)
			(layer "F.Fab")
		)
		(fp_circle
			(center -0.4699 -0.8382)
			(end -0.5969 -0.8382)
			(stroke
				(width 0.254)
				(type default)
			)
			(fill no)
			(layer "F.Fab")
		)
		(pad "1" smd rect
			(at 0 0 180)
			(size 1.016 0.381)
			(layers "F.Cu" "F.Mask" "F.Paste")
			(net "Net_6471")
		)
		(pad "2" smd rect
			(at 0 0.649986 180)
			(size 1.016 0.381)
			(layers "F.Cu" "F.Mask" "F.Paste")
			(net "IRQ_SML1_PMBUS_ALERT_BUF_N")
		)
		(pad "3" smd rect
			(at 0 1.299972 180)
			(size 1.016 0.381)
			(layers "F.Cu" "F.Mask" "F.Paste")
			(net "GND")
		)
		(pad "4" smd rect
			(at 1.778 1.299972 180)
			(size 1.016 0.381)
			(layers "F.Cu" "F.Mask" "F.Paste")
			(net "IRQ_FORCE_NM_THROTTLE_R_N")
		)
		(pad "5" smd rect
			(at 1.778 0 180)
			(size 1.016 0.381)
			(layers "F.Cu" "F.Mask" "F.Paste")
			(net "P3V3_STBY")
		)
	)
	(footprint ""
		(layer "F.Cu")
		(at 6.9342 -130.302 180)
		(property "Reference" "C1B6"
			(at -0.8382 -0.67818 180)
			(unlocked yes)
			(layer "F.SilkS")
			(effects
				(font
					(size 0.4064 0.254)
					(thickness 0.1524)
				)
				(justify left)
			)
		)
		(property "Value" ""
			(at 0 0 180)
			(layer "F.Fab")
			(effects
				(font
					(size 1.27 1.27)
				)
			)
		)
		(duplicate_pad_numbers_are_jumpers no)
		(fp_poly
			(pts
				(xy 0.3048 -0.1016) (xy 0.3048 0.9906) (xy -0.3048 0.9906) (xy -0.3048 -0.1016)
			)
			(stroke
				(width 0)
				(type default)
			)
			(fill no)
			(layer "F.CrtYd")
		)
		(fp_line
			(start 0.3048 0.9906)
			(end 0.3048 -0.1016)
			(stroke
				(width 0.1)
				(type default)
			)
			(layer "F.Fab")
		)
		(fp_line
			(start 0.3048 -0.1016)
			(end -0.3048 -0.1016)
			(stroke
				(width 0.1)
				(type default)
			)
			(layer "F.Fab")
		)
		(fp_line
			(start -0.3048 0.9906)
			(end 0.3048 0.9906)
			(stroke
				(width 0.1)
				(type default)
			)
			(layer "F.Fab")
		)
		(fp_line
			(start -0.3048 -0.1016)
			(end -0.3048 0.9906)
			(stroke
				(width 0.1)
				(type default)
			)
			(layer "F.Fab")
		)
		(pad "1" smd rect
			(at 0 0 180)
			(size 0.508 0.508)
			(layers "F.Cu" "F.Mask" "F.Paste")
			(net "VR_PVDDQ_KLM_VDD")
		)
		(pad "2" smd rect
			(at 0 0.889 180)
			(size 0.508 0.508)
			(layers "F.Cu" "F.Mask" "F.Paste")
			(net "GND")
		)
		(zone
			(layer "F.Cu")
			(hatch none 0.5)
			(connect_pads
				(clearance 0)
			)
			(min_thickness 0.25)
			(keepout
				(tracks not_allowed)
				(vias allowed)
				(pads allowed)
				(copperpour not_allowed)
				(footprints allowed)
			)
			(placement
				(enabled no)
				(sheetname "")
			)
			(fill
				(thermal_gap 0.5)
				(thermal_bridge_width 0.5)
				(island_removal_mode 0)
			)
			(polygon
				(pts
					(xy 7.1882 -130.937) (xy 6.6802 -130.937) (xy 6.6802 -130.556) (xy 7.1882 -130.556)
				)
			)
		)
		(zone
			(layer "F.Cu")
			(hatch none 0.5)
			(connect_pads
				(clearance 0)
			)
			(min_thickness 0.25)
			(keepout
				(tracks allowed)
				(vias not_allowed)
				(pads allowed)
				(copperpour not_allowed)
				(footprints allowed)
			)
			(placement
				(enabled no)
				(sheetname "")
			)
			(fill
				(thermal_gap 0.5)
				(thermal_bridge_width 0.5)
				(island_removal_mode 0)
			)
			(polygon
				(pts
					(xy 7.1882 -130.556) (xy 6.6802 -130.556) (xy 6.6802 -130.937) (xy 7.1882 -130.937)
				)
			)
		)
	)
)
